(kicad_pcb
	(version 20260206)
	(generator "pcbnew")
	(generator_version "10.0")
	(general
		(thickness 1.6)
		(legacy_teardrops no)
	)
	(paper "A4")
	(title_block
		(title "Bryce Canyon_R.DPB_16317-1_OCP.brd")
		(comment 1 "Bryce Canyon / footprints 475-482 of 2099")
	)
	(layers
		(0 "F.Cu" signal "TOP")
		(4 "In1.Cu" signal "L2GND")
		(6 "In2.Cu" signal "L3")
		(8 "In3.Cu" signal "L4VCC")
		(10 "In4.Cu" signal "L5VCC")
		(12 "In5.Cu" signal "L6")
		(14 "In6.Cu" signal "L7GND")
		(2 "B.Cu" signal "BOTTOM")
		(9 "F.Adhes" user "F.Adhesive")
		(11 "B.Adhes" user "B.Adhesive")
		(13 "F.Paste" user "Package Geometry/Pastemask Top")
		(15 "B.Paste" user "Package Geometry/Pastemask Bottom")
		(5 "F.SilkS" user "Ref Des/Silkscreen Top")
		(7 "B.SilkS" user "Ref Des/Silkscreen Bottom")
		(1 "F.Mask" user "Board Geometry/Soldermask Top")
		(3 "B.Mask" user "Board Geometry/Soldermask Bottom")
		(17 "Dwgs.User" user "User.Drawings")
		(19 "Cmts.User" user "User.Comments")
		(21 "Eco1.User" user "User.Eco1")
		(23 "Eco2.User" user "User.Eco2")
		(25 "Edge.Cuts" user "Board Geometry/Outline")
		(27 "Margin" user)
		(31 "F.CrtYd" user "Package Geometry/Place Bound Top")
		(29 "B.CrtYd" user "Package Geometry/Place Bound Bottom")
		(35 "F.Fab" user "Ref Des/Assembly Top")
		(33 "B.Fab" user "Ref Des/Assembly Bottom")
	)
	(footprint ""
		(layer "F.Cu")
		(at 459.359 -243.586 180)
		(property "Reference" "R324"
			(at 0 0 180)
			(layer "F.SilkS")
			(hide yes)
			(effects
				(font
					(size 1.27 1.27)
				)
			)
		)
		(property "Value" "1KR2F-3-GP"
			(at 0.064008 -3.993896 180)
			(unlocked yes)
			(layer "F.Fab")
			(hide yes)
			(effects
				(font
					(size 1.016 1.016)
					(thickness 0.1524)
				)
			)
		)
		(property "Device Type" "R402H16"
			(at 0.064008 -5.517896 180)
			(unlocked yes)
			(layer "F.Fab")
			(hide yes)
			(effects
				(font
					(size 1.016 1.016)
					(thickness 0.1524)
				)
			)
		)
		(duplicate_pad_numbers_are_jumpers no)
		(fp_line
			(start 0.508 -0.9398)
			(end -0.508 -0.9398)
			(stroke
				(width 0.1524)
				(type default)
			)
			(layer "F.SilkS")
		)
		(fp_line
			(start -0.508 -0.9398)
			(end -0.508 0.9398)
			(stroke
				(width 0.1524)
				(type default)
			)
			(layer "F.SilkS")
		)
		(fp_rect
			(start -0.508 0.9398)
			(end 0.508 -0.9398)
			(stroke
				(width 0)
				(type default)
			)
			(fill no)
			(layer "F.CrtYd")
		)
		(fp_rect
			(start -0.508 0.9398)
			(end 0.508 -0.9398)
			(stroke
				(width 0)
				(type default)
			)
			(fill no)
			(layer "F.Fab")
		)
		(pad "1" smd custom
			(at 0 -0.4445 180)
			(size 0.1397 0.1397)
			(layers "F.Cu" "F.Mask" "F.Paste")
			(net "P3V3_STBY_B")
			(options
				(clearance outline)
				(anchor circle)
			)
			(primitives
				(gr_poly
					(pts
						(arc
							(start -0.1778 -0.2794)
							(mid -0.249642 -0.249642)
							(end -0.2794 -0.1778)
						)
						(arc
							(start -0.2794 0.1778)
							(mid -0.249642 0.249642)
							(end -0.1778 0.2794)
						)
						(arc
							(start 0.1778 0.2794)
							(mid 0.249642 0.249642)
							(end 0.2794 0.1778)
						)
						(arc
							(start 0.2794 -0.1778)
							(mid 0.249642 -0.249642)
							(end 0.1778 -0.2794)
						)
					)
					(width 0)
					(fill yes)
				)
			)
		)
		(pad "2" smd custom
			(at 0 0.4445 180)
			(size 0.1397 0.1397)
			(layers "F.Cu" "F.Mask" "F.Paste")
			(net "SW_PWR_R_HDD10")
			(options
				(clearance outline)
				(anchor circle)
			)
			(primitives
				(gr_poly
					(pts
						(arc
							(start -0.1778 -0.2794)
							(mid -0.249642 -0.249642)
							(end -0.2794 -0.1778)
						)
						(arc
							(start -0.2794 0.1778)
							(mid -0.249642 0.249642)
							(end -0.1778 0.2794)
						)
						(arc
							(start 0.1778 0.2794)
							(mid 0.249642 0.249642)
							(end 0.2794 0.1778)
						)
						(arc
							(start 0.2794 -0.1778)
							(mid 0.249642 -0.249642)
							(end 0.1778 -0.2794)
						)
					)
					(width 0)
					(fill yes)
				)
			)
		)
	)
	(footprint ""
		(layer "F.Cu")
		(at 79.883 -23.114 90)
		(property "Reference" "R675"
			(at 0 0 90)
			(layer "F.SilkS")
			(hide yes)
			(effects
				(font
					(size 1.27 1.27)
				)
			)
		)
		(property "Value" "4K7R2J-2-GP"
			(at 0.064008 -3.993896 90)
			(unlocked yes)
			(layer "F.Fab")
			(hide yes)
			(effects
				(font
					(size 1.016 1.016)
					(thickness 0.1524)
				)
			)
		)
		(property "Device Type" "R402H16"
			(at 0.064008 -5.517896 90)
			(unlocked yes)
			(layer "F.Fab")
			(hide yes)
			(effects
				(font
					(size 1.016 1.016)
					(thickness 0.1524)
				)
			)
		)
		(duplicate_pad_numbers_are_jumpers no)
		(fp_line
			(start 0.508 -0.9398)
			(end -0.508 -0.9398)
			(stroke
				(width 0.1524)
				(type default)
			)
			(layer "F.SilkS")
		)
		(fp_line
			(start -0.508 -0.9398)
			(end -0.508 0.9398)
			(stroke
				(width 0.1524)
				(type default)
			)
			(layer "F.SilkS")
		)
		(fp_rect
			(start -0.508 0.9398)
			(end 0.508 -0.9398)
			(stroke
				(width 0)
				(type default)
			)
			(fill no)
			(layer "F.CrtYd")
		)
		(fp_rect
			(start -0.508 0.9398)
			(end 0.508 -0.9398)
			(stroke
				(width 0)
				(type default)
			)
			(fill no)
			(layer "F.Fab")
		)
		(pad "1" smd custom
			(at 0 -0.4445 90)
			(size 0.1397 0.1397)
			(layers "F.Cu" "F.Mask" "F.Paste")
			(net "P12V_B")
			(options
				(clearance outline)
				(anchor circle)
			)
			(primitives
				(gr_poly
					(pts
						(arc
							(start -0.1778 -0.2794)
							(mid -0.249642 -0.249642)
							(end -0.2794 -0.1778)
						)
						(arc
							(start -0.2794 0.1778)
							(mid -0.249642 0.249642)
							(end -0.1778 0.2794)
						)
						(arc
							(start 0.1778 0.2794)
							(mid 0.249642 0.249642)
							(end 0.2794 0.1778)
						)
						(arc
							(start 0.2794 -0.1778)
							(mid 0.249642 -0.249642)
							(end 0.1778 -0.2794)
						)
					)
					(width 0)
					(fill yes)
				)
			)
		)
		(pad "2" smd custom
			(at 0 0.4445 90)
			(size 0.1397 0.1397)
			(layers "F.Cu" "F.Mask" "F.Paste")
			(net "SW_HDD_P26")
			(options
				(clearance outline)
				(anchor circle)
			)
			(primitives
				(gr_poly
					(pts
						(arc
							(start -0.1778 -0.2794)
							(mid -0.249642 -0.249642)
							(end -0.2794 -0.1778)
						)
						(arc
							(start -0.2794 0.1778)
							(mid -0.249642 0.249642)
							(end -0.1778 0.2794)
						)
						(arc
							(start 0.1778 0.2794)
							(mid 0.249642 0.249642)
							(end 0.2794 0.1778)
						)
						(arc
							(start 0.2794 -0.1778)
							(mid 0.249642 -0.249642)
							(end 0.1778 -0.2794)
						)
					)
					(width 0)
					(fill yes)
				)
			)
		)
	)
	(footprint ""
		(layer "F.Cu")
		(at 251.941838 -229.48011 90)
		(property "Reference" "R133"
			(at 0 0 90)
			(layer "F.SilkS")
			(hide yes)
			(effects
				(font
					(size 1.27 1.27)
				)
			)
		)
		(property "Value" "7K32R2F-GP"
			(at 0.064008 -3.993896 90)
			(unlocked yes)
			(layer "F.Fab")
			(hide yes)
			(effects
				(font
					(size 1.016 1.016)
					(thickness 0.1524)
				)
			)
		)
		(property "Device Type" "R402H16"
			(at 0.064008 -5.517896 90)
			(unlocked yes)
			(layer "F.Fab")
			(hide yes)
			(effects
				(font
					(size 1.016 1.016)
					(thickness 0.1524)
				)
			)
		)
		(duplicate_pad_numbers_are_jumpers no)
		(fp_line
			(start 0.508 -0.9398)
			(end -0.508 -0.9398)
			(stroke
				(width 0.1524)
				(type default)
			)
			(layer "F.SilkS")
		)
		(fp_line
			(start -0.508 -0.9398)
			(end -0.508 0.9398)
			(stroke
				(width 0.1524)
				(type default)
			)
			(layer "F.SilkS")
		)
		(fp_rect
			(start -0.508 0.9398)
			(end 0.508 -0.9398)
			(stroke
				(width 0)
				(type default)
			)
			(fill no)
			(layer "F.CrtYd")
		)
		(fp_rect
			(start -0.508 0.9398)
			(end 0.508 -0.9398)
			(stroke
				(width 0)
				(type default)
			)
			(fill no)
			(layer "F.Fab")
		)
		(pad "1" smd custom
			(at 0 -0.4445 90)
			(size 0.1397 0.1397)
			(layers "F.Cu" "F.Mask" "F.Paste")
			(net "P3V3_STBY_B")
			(options
				(clearance outline)
				(anchor circle)
			)
			(primitives
				(gr_poly
					(pts
						(arc
							(start -0.1778 -0.2794)
							(mid -0.249642 -0.249642)
							(end -0.2794 -0.1778)
						)
						(arc
							(start -0.2794 0.1778)
							(mid -0.249642 0.249642)
							(end -0.1778 0.2794)
						)
						(arc
							(start 0.1778 0.2794)
							(mid 0.249642 0.249642)
							(end 0.2794 0.1778)
						)
						(arc
							(start 0.2794 -0.1778)
							(mid 0.249642 -0.249642)
							(end 0.1778 -0.2794)
						)
					)
					(width 0)
					(fill yes)
				)
			)
		)
		(pad "2" smd custom
			(at 0 0.4445 90)
			(size 0.1397 0.1397)
			(layers "F.Cu" "F.Mask" "F.Paste")
			(net "P3V3_SENSE")
			(options
				(clearance outline)
				(anchor circle)
			)
			(primitives
				(gr_poly
					(pts
						(arc
							(start -0.1778 -0.2794)
							(mid -0.249642 -0.249642)
							(end -0.2794 -0.1778)
						)
						(arc
							(start -0.2794 0.1778)
							(mid -0.249642 0.249642)
							(end -0.1778 0.2794)
						)
						(arc
							(start 0.1778 0.2794)
							(mid 0.249642 0.249642)
							(end 0.2794 0.1778)
						)
						(arc
							(start 0.2794 -0.1778)
							(mid 0.249642 -0.249642)
							(end 0.1778 -0.2794)
						)
					)
					(width 0)
					(fill yes)
				)
			)
		)
	)
	(footprint ""
		(layer "F.Cu")
		(at 413.866076 -39.705026)
		(property "Reference" "TP186"
			(at 0 0 0)
			(layer "F.SilkS")
			(hide yes)
			(effects
				(font
					(size 1.27 1.27)
				)
			)
		)
		(property "Value" "*"
			(at -0.0508 -1.6764 0)
			(unlocked yes)
			(layer "F.Fab")
			(hide yes)
			(effects
				(font
					(size 1.016 1.016)
					(thickness 0.1524)
				)
			)
		)
		(property "Device Type" "TPAD32"
			(at -0.0508 -3.2004 0)
			(unlocked yes)
			(layer "F.Fab")
			(hide yes)
			(effects
				(font
					(size 1.016 1.016)
					(thickness 0.1524)
				)
			)
		)
		(duplicate_pad_numbers_are_jumpers no)
		(fp_poly
			(pts
				(arc
					(start 0.4064 0)
					(mid -0.4064 0)
					(end 0.4064 0)
				)
			)
			(stroke
				(width 0)
				(type default)
			)
			(fill no)
			(layer "F.CrtYd")
		)
		(fp_poly
			(pts
				(arc
					(start 0.7112 0)
					(mid -0.7112 0)
					(end 0.7112 0)
				)
			)
			(stroke
				(width 0)
				(type default)
			)
			(fill no)
			(layer "F.Fab")
		)
		(pad "1" smd circle
			(at 0 0)
			(size 0.8128 0.8128)
			(layers "F.Cu" "F.Mask" "F.Paste")
			(net "ACT_HDD_33")
		)
	)
	(footprint ""
		(layer "F.Cu")
		(at 363.855 -266.827 180)
		(property "Reference" "C122"
			(at 0 0 180)
			(layer "F.SilkS")
			(hide yes)
			(effects
				(font
					(size 1.27 1.27)
				)
			)
		)
		(property "Value" "SC10U16V6KX-2GP"
			(at -0.0762 -5.1308 180)
			(unlocked yes)
			(layer "F.Fab")
			(hide yes)
			(effects
				(font
					(size 1.016 1.016)
					(thickness 0.1524)
				)
			)
		)
		(property "Device Type" "C1206H71"
			(at -0.127 -6.6548 180)
			(unlocked yes)
			(layer "F.Fab")
			(hide yes)
			(effects
				(font
					(size 1.016 1.016)
					(thickness 0.1524)
				)
			)
		)
		(duplicate_pad_numbers_are_jumpers no)
		(fp_line
			(start 1.016 2.2352)
			(end -1.016 2.2352)
			(stroke
				(width 0.1524)
				(type default)
			)
			(layer "F.SilkS")
		)
		(fp_line
			(start 1.016 0.8382)
			(end 1.016 2.2352)
			(stroke
				(width 0.1524)
				(type default)
			)
			(layer "F.SilkS")
		)
		(fp_line
			(start 1.016 -2.2352)
			(end 1.016 -0.8382)
			(stroke
				(width 0.1524)
				(type default)
			)
			(layer "F.SilkS")
		)
		(fp_line
			(start -1.016 2.2352)
			(end -1.016 0.8382)
			(stroke
				(width 0.1524)
				(type default)
			)
			(layer "F.SilkS")
		)
		(fp_line
			(start -1.016 -0.8382)
			(end -1.016 -2.2352)
			(stroke
				(width 0.1524)
				(type default)
			)
			(layer "F.SilkS")
		)
		(fp_line
			(start -1.016 -2.2352)
			(end 1.016 -2.2352)
			(stroke
				(width 0.1524)
				(type default)
			)
			(layer "F.SilkS")
		)
		(fp_rect
			(start -1.0922 2.3114)
			(end 1.0922 -2.3114)
			(stroke
				(width 0)
				(type default)
			)
			(fill no)
			(layer "F.CrtYd")
		)
		(fp_poly
			(pts
				(xy 1.0922 -2.3114) (xy 1.0922 2.3114) (xy -1.0922 2.3114) (xy -1.0922 -2.3114)
			)
			(stroke
				(width 0)
				(type default)
			)
			(fill no)
			(layer "F.Fab")
		)
		(pad "1" smd rect
			(at 0 -1.397 180)
			(size 1.651 1.27)
			(layers "F.Cu" "F.Mask" "F.Paste")
			(net "P5V_HDD7")
		)
		(pad "2" smd rect
			(at 0 1.397 180)
			(size 1.651 1.27)
			(layers "F.Cu" "F.Mask" "F.Paste")
			(net "GND")
		)
	)
	(footprint ""
		(layer "F.Cu")
		(at 158.663386 -15.219426 90)
		(property "Reference" "C392"
			(at 0 0 90)
			(layer "F.SilkS")
			(hide yes)
			(effects
				(font
					(size 1.27 1.27)
				)
			)
		)
		(property "Value" "SCD01U16V1KX-GP"
			(at -2.8321 -1.7399 90)
			(unlocked yes)
			(layer "F.Fab")
			(hide yes)
			(effects
				(font
					(size 1.016 1.016)
					(thickness 0.1524)
				)
			)
		)
		(property "Device Type" "C0201H13"
			(at -2.8321 -3.2639 90)
			(unlocked yes)
			(layer "F.Fab")
			(hide yes)
			(effects
				(font
					(size 1.016 1.016)
					(thickness 0.1524)
				)
			)
		)
		(duplicate_pad_numbers_are_jumpers no)
		(fp_rect
			(start -0.2794 0.6477)
			(end 0.2794 -0.6477)
			(stroke
				(width 0)
				(type default)
			)
			(fill no)
			(layer "F.CrtYd")
		)
		(fp_rect
			(start -0.2794 0.6477)
			(end 0.2794 -0.6477)
			(stroke
				(width 0)
				(type default)
			)
			(fill no)
			(layer "F.Fab")
		)
		(pad "1" smd custom
			(at 0 -0.2794 90)
			(size 0.0762 0.0762)
			(layers "F.Cu" "F.Mask" "F.Paste")
			(net "SAS_HDD_RX_N28")
			(options
				(clearance outline)
				(anchor circle)
			)
			(primitives
				(gr_poly
					(pts
						(arc
							(start 0.1524 -0.127)
							(mid 0.137521 -0.162921)
							(end 0.1016 -0.1778)
						)
						(arc
							(start -0.1016 -0.1778)
							(mid -0.137521 -0.162921)
							(end -0.1524 -0.127)
						)
						(arc
							(start -0.1524 0.127)
							(mid -0.137521 0.162921)
							(end -0.1016 0.1778)
						)
						(arc
							(start 0.1016 0.1778)
							(mid 0.137521 0.162921)
							(end 0.1524 0.127)
						)
					)
					(width 0)
					(fill yes)
				)
			)
		)
		(pad "2" smd custom
			(at 0 0.2794 90)
			(size 0.0762 0.0762)
			(layers "F.Cu" "F.Mask" "F.Paste")
			(net "PHY_SCC_B_TO_DRV_B_28_DN")
			(options
				(clearance outline)
				(anchor circle)
			)
			(primitives
				(gr_poly
					(pts
						(arc
							(start 0.1524 -0.127)
							(mid 0.137521 -0.162921)
							(end 0.1016 -0.1778)
						)
						(arc
							(start -0.1016 -0.1778)
							(mid -0.137521 -0.162921)
							(end -0.1524 -0.127)
						)
						(arc
							(start -0.1524 0.127)
							(mid -0.137521 0.162921)
							(end -0.1016 0.1778)
						)
						(arc
							(start 0.1016 0.1778)
							(mid 0.137521 0.162921)
							(end 0.1524 0.127)
						)
					)
					(width 0)
					(fill yes)
				)
			)
		)
	)
	(footprint ""
		(layer "F.Cu")
		(at 247.965468 -223.393 180)
		(property "Reference" "R108"
			(at 0 0 180)
			(layer "F.SilkS")
			(hide yes)
			(effects
				(font
					(size 1.27 1.27)
				)
			)
		)
		(property "Value" "4K7R2F-GP"
			(at 0.064008 -3.993896 180)
			(unlocked yes)
			(layer "F.Fab")
			(hide yes)
			(effects
				(font
					(size 1.016 1.016)
					(thickness 0.1524)
				)
			)
		)
		(property "Device Type" "R402H16"
			(at 0.064008 -5.517896 180)
			(unlocked yes)
			(layer "F.Fab")
			(hide yes)
			(effects
				(font
					(size 1.016 1.016)
					(thickness 0.1524)
				)
			)
		)
		(duplicate_pad_numbers_are_jumpers no)
		(fp_line
			(start 0.508 -0.9398)
			(end -0.508 -0.9398)
			(stroke
				(width 0.1524)
				(type default)
			)
			(layer "F.SilkS")
		)
		(fp_line
			(start -0.508 -0.9398)
			(end -0.508 0.9398)
			(stroke
				(width 0.1524)
				(type default)
			)
			(layer "F.SilkS")
		)
		(fp_rect
			(start -0.508 0.9398)
			(end 0.508 -0.9398)
			(stroke
				(width 0)
				(type default)
			)
			(fill no)
			(layer "F.CrtYd")
		)
		(fp_rect
			(start -0.508 0.9398)
			(end 0.508 -0.9398)
			(stroke
				(width 0)
				(type default)
			)
			(fill no)
			(layer "F.Fab")
		)
		(pad "1" smd custom
			(at 0 -0.4445 180)
			(size 0.1397 0.1397)
			(layers "F.Cu" "F.Mask" "F.Paste")
			(net "EEPROM_A2")
			(options
				(clearance outline)
				(anchor circle)
			)
			(primitives
				(gr_poly
					(pts
						(arc
							(start -0.1778 -0.2794)
							(mid -0.249642 -0.249642)
							(end -0.2794 -0.1778)
						)
						(arc
							(start -0.2794 0.1778)
							(mid -0.249642 0.249642)
							(end -0.1778 0.2794)
						)
						(arc
							(start 0.1778 0.2794)
							(mid 0.249642 0.249642)
							(end 0.2794 0.1778)
						)
						(arc
							(start 0.2794 -0.1778)
							(mid 0.249642 -0.249642)
							(end 0.1778 -0.2794)
						)
					)
					(width 0)
					(fill yes)
				)
			)
		)
		(pad "2" smd custom
			(at 0 0.4445 180)
			(size 0.1397 0.1397)
			(layers "F.Cu" "F.Mask" "F.Paste")
			(net "GND")
			(options
				(clearance outline)
				(anchor circle)
			)
			(primitives
				(gr_poly
					(pts
						(arc
							(start -0.1778 -0.2794)
							(mid -0.249642 -0.249642)
							(end -0.2794 -0.1778)
						)
						(arc
							(start -0.2794 0.1778)
							(mid -0.249642 0.249642)
							(end -0.1778 0.2794)
						)
						(arc
							(start 0.1778 0.2794)
							(mid 0.249642 0.249642)
							(end 0.2794 0.1778)
						)
						(arc
							(start 0.2794 -0.1778)
							(mid 0.249642 -0.249642)
							(end 0.1778 -0.2794)
						)
					)
					(width 0)
					(fill yes)
				)
			)
		)
	)
	(footprint ""
		(layer "F.Cu")
		(at 149.987 -33.274)
		(property "Reference" "R713"
			(at 0 0 0)
			(layer "F.SilkS")
			(hide yes)
			(effects
				(font
					(size 1.27 1.27)
				)
			)
		)
		(property "Value" "2R6F-GP"
			(at -0.0508 -4.8514 0)
			(unlocked yes)
			(layer "F.Fab")
			(hide yes)
			(effects
				(font
					(size 1.016 1.016)
					(thickness 0.1524)
				)
			)
		)
		(property "Device Type" "R1206H26"
			(at 0 -6.3754 0)
			(unlocked yes)
			(layer "F.Fab")
			(hide yes)
			(effects
				(font
					(size 1.016 1.016)
					(thickness 0.1524)
				)
			)
		)
		(duplicate_pad_numbers_are_jumpers no)
		(fp_line
			(start -1.016 -2.2352)
			(end 1.016 -2.2352)
			(stroke
				(width 0.1524)
				(type default)
			)
			(layer "F.SilkS")
		)
		(fp_line
			(start -1.016 2.2352)
			(end -1.016 -2.2352)
			(stroke
				(width 0.1524)
				(type default)
			)
			(layer "F.SilkS")
		)
		(fp_line
			(start 1.016 -2.2352)
			(end 1.016 2.2352)
			(stroke
				(width 0.1524)
				(type default)
			)
			(layer "F.SilkS")
		)
		(fp_line
			(start 1.016 2.2352)
			(end -1.016 2.2352)
			(stroke
				(width 0.1524)
				(type default)
			)
			(layer "F.SilkS")
		)
		(fp_rect
			(start -1.0922 2.3114)
			(end 1.0922 -2.3114)
			(stroke
				(width 0)
				(type default)
			)
			(fill no)
			(layer "F.CrtYd")
		)
		(fp_poly
			(pts
				(xy -1.0922 -2.3114) (xy 1.0922 -2.3114) (xy 1.0922 2.3114) (xy -1.0922 2.3114)
			)
			(stroke
				(width 0)
				(type default)
			)
			(fill no)
			(layer "F.Fab")
		)
		(pad "1" smd rect
			(at 0 -1.397)
			(size 1.651 1.27)
			(layers "F.Cu" "F.Mask" "F.Paste")
			(net "P5V_HDD28")
		)
		(pad "2" smd rect
			(at 0 1.397)
			(size 1.651 1.27)
			(layers "F.Cu" "F.Mask" "F.Paste")
			(net "5V_PRE_28")
		)
	)
)
